# S9S_MB_2U (Grand Teton) — schematic netlist excerpt (pin names and nets, part order shuffled) for the footprints in the layout excerpt that follows; sources: Cadence DE-HDL packaged netlist, KiCad conversion of 03242023_DA0F0TMBIJ0_F0T_Motherboard_J_brd_V01_OCP.brd

R3880  Q_RES  49.9 1% CHIP  pkg 0402LF  page 87 : A = I3C_SPD_DDRABCD_CPU0_LVC1_SCL_5 ; B = I3C_SPD_DDRABCD_CPU0_LVC1_SCL
R1541  Q_RES  100K 1% CHIP  pkg 0402LF  page 223 : A = GND ; B = RST_PLTRST_N

(kicad_pcb
	(version 20260206)
	(generator "pcbnew")
	(generator_version "10.0")
	(general
		(thickness 1.6)
		(legacy_teardrops no)
	)
	(paper "A4")
	(title_block
		(title "03242023_DA0F0TMBIJ0_F0T_Motherboard_J_brd_V01_OCP.brd")
		(comment 1 "Grand Teton / footprints 4836-4837 of 6105")
	)
	(layers
		(0 "F.Cu" signal "TOP")
		(4 "In1.Cu" signal "GND")
		(6 "In2.Cu" signal "IN1")
		(8 "In3.Cu" signal "GND1")
		(10 "In4.Cu" signal "IN2")
		(12 "In5.Cu" signal "GND2")
		(14 "In6.Cu" signal "IN3")
		(16 "In7.Cu" signal "GND3")
		(18 "In8.Cu" signal "VCC")
		(20 "In9.Cu" signal "VCC1")
		(22 "In10.Cu" signal "GND4")
		(24 "In11.Cu" signal "IN4")
		(26 "In12.Cu" signal "GND5")
		(28 "In13.Cu" signal "IN5")
		(30 "In14.Cu" signal "GND6")
		(32 "In15.Cu" signal "IN6")
		(34 "In16.Cu" signal "GND7")
		(2 "B.Cu" signal "BOTTOM")
		(9 "F.Adhes" user "F.Adhesive")
		(11 "B.Adhes" user "B.Adhesive")
		(13 "F.Paste" user "Package Geometry/Pastemask Top")
		(15 "B.Paste" user "Package Geometry/Pastemask Bottom")
		(5 "F.SilkS" user "Ref Des/Silkscreen Top")
		(7 "B.SilkS" user "Ref Des/Silkscreen Bottom")
		(1 "F.Mask" user "Board Geometry/Soldermask Top")
		(3 "B.Mask" user "Board Geometry/Soldermask Bottom")
		(17 "Dwgs.User" user "User.Drawings")
		(19 "Cmts.User" user "User.Comments")
		(21 "Eco1.User" user "User.Eco1")
		(23 "Eco2.User" user "User.Eco2")
		(25 "Edge.Cuts" user "Board Geometry/Outline")
		(27 "Margin" user)
		(31 "F.CrtYd" user "Package Geometry/Place Bound Top")
		(29 "B.CrtYd" user "Package Geometry/Place Bound Bottom")
		(35 "F.Fab" user "Ref Des/Assembly Top")
		(33 "B.Fab" user "Ref Des/Assembly Bottom")
	)
	(footprint ""
		(layer "B.Cu")
		(at 197.19036 -120.614948)
		(property "Reference" "R1541"
			(at 0 0 0)
			(layer "B.SilkS")
			(hide yes)
			(effects
				(font
					(size 1.27 1.27)
				)
				(justify mirror)
			)
		)
		(property "Value" ""
			(at 0 0 0)
			(layer "B.Fab")
			(effects
				(font
					(size 1.27 1.27)
				)
				(justify mirror)
			)
		)
		(duplicate_pad_numbers_are_jumpers no)
		(fp_line
			(start -0.7874 -0.4064)
			(end -0.7874 0.4064)
			(stroke
				(width 0.1524)
				(type default)
			)
			(layer "B.SilkS")
		)
		(fp_line
			(start -0.7874 0.4064)
			(end 0.7874 0.4064)
			(stroke
				(width 0.1524)
				(type default)
			)
			(layer "B.SilkS")
		)
		(fp_line
			(start 0.7874 -0.4064)
			(end -0.7874 -0.4064)
			(stroke
				(width 0.1524)
				(type default)
			)
			(layer "B.SilkS")
		)
		(fp_line
			(start 0.7874 0.4064)
			(end 0.7874 -0.4064)
			(stroke
				(width 0.1524)
				(type default)
			)
			(layer "B.SilkS")
		)
		(fp_line
			(start -0.67945 -0.3048)
			(end -0.67945 0.3048)
			(stroke
				(width 0.1)
				(type default)
			)
			(layer "B.Fab")
		)
		(fp_line
			(start -0.67945 0.3048)
			(end -0.120396 0.3048)
			(stroke
				(width 0.1)
				(type default)
			)
			(layer "B.Fab")
		)
		(fp_line
			(start -0.12065 -0.3048)
			(end -0.67945 -0.3048)
			(stroke
				(width 0.1)
				(type default)
			)
			(layer "B.Fab")
		)
		(fp_line
			(start -0.12065 -0.2794)
			(end -0.12065 -0.3048)
			(stroke
				(width 0.1)
				(type default)
			)
			(layer "B.Fab")
		)
		(fp_line
			(start -0.120396 0.2794)
			(end 0.12065 0.2794)
			(stroke
				(width 0.1)
				(type default)
			)
			(layer "B.Fab")
		)
		(fp_line
			(start -0.120396 0.3048)
			(end -0.120396 0.2794)
			(stroke
				(width 0.1)
				(type default)
			)
			(layer "B.Fab")
		)
		(fp_line
			(start 0.12065 -0.305054)
			(end 0.12065 -0.2794)
			(stroke
				(width 0.1)
				(type default)
			)
			(layer "B.Fab")
		)
		(fp_line
			(start 0.12065 -0.2794)
			(end -0.12065 -0.2794)
			(stroke
				(width 0.1)
				(type default)
			)
			(layer "B.Fab")
		)
		(fp_line
			(start 0.12065 0.2794)
			(end 0.12065 0.3048)
			(stroke
				(width 0.1)
				(type default)
			)
			(layer "B.Fab")
		)
		(fp_line
			(start 0.12065 0.3048)
			(end 0.67945 0.3048)
			(stroke
				(width 0.1)
				(type default)
			)
			(layer "B.Fab")
		)
		(fp_line
			(start 0.67945 -0.305054)
			(end 0.12065 -0.305054)
			(stroke
				(width 0.1)
				(type default)
			)
			(layer "B.Fab")
		)
		(fp_line
			(start 0.67945 0.3048)
			(end 0.67945 -0.305054)
			(stroke
				(width 0.1)
				(type default)
			)
			(layer "B.Fab")
		)
		(pad "1" smd circle
			(at 0.40005 0 180)
			(size 0 0)
			(layers "B.Cu" "B.Mask" "B.Paste")
			(net "GND")
		)
		(pad "2" smd circle
			(at -0.40005 0 180)
			(size 0 0)
			(layers "B.Cu" "B.Mask" "B.Paste")
			(net "RST_PLTRST_N")
		)
	)
	(footprint ""
		(layer "B.Cu")
		(at 277.868888 -317.857886 180)
		(property "Reference" "R3880"
			(at 0 0 0)
			(layer "B.SilkS")
			(hide yes)
			(effects
				(font
					(size 1.27 1.27)
				)
				(justify mirror)
			)
		)
		(property "Value" ""
			(at 0 0 0)
			(layer "B.Fab")
			(effects
				(font
					(size 1.27 1.27)
				)
				(justify mirror)
			)
		)
		(duplicate_pad_numbers_are_jumpers no)
		(fp_line
			(start 0.7874 0.4064)
			(end 0.7874 -0.4064)
			(stroke
				(width 0.1524)
				(type default)
			)
			(layer "B.SilkS")
		)
		(fp_line
			(start 0.7874 -0.4064)
			(end -0.7874 -0.4064)
			(stroke
				(width 0.1524)
				(type default)
			)
			(layer "B.SilkS")
		)
		(fp_line
			(start -0.7874 0.4064)
			(end 0.7874 0.4064)
			(stroke
				(width 0.1524)
				(type default)
			)
			(layer "B.SilkS")
		)
		(fp_line
			(start -0.7874 -0.4064)
			(end -0.7874 0.4064)
			(stroke
				(width 0.1524)
				(type default)
			)
			(layer "B.SilkS")
		)
		(fp_line
			(start 0.67945 0.3048)
			(end 0.67945 -0.305054)
			(stroke
				(width 0.1)
				(type default)
			)
			(layer "B.Fab")
		)
		(fp_line
			(start 0.67945 -0.305054)
			(end 0.12065 -0.305054)
			(stroke
				(width 0.1)
				(type default)
			)
			(layer "B.Fab")
		)
		(fp_line
			(start 0.12065 0.3048)
			(end 0.67945 0.3048)
			(stroke
				(width 0.1)
				(type default)
			)
			(layer "B.Fab")
		)
		(fp_line
			(start 0.12065 0.2794)
			(end 0.12065 0.3048)
			(stroke
				(width 0.1)
				(type default)
			)
			(layer "B.Fab")
		)
		(fp_line
			(start 0.12065 -0.2794)
			(end -0.12065 -0.2794)
			(stroke
				(width 0.1)
				(type default)
			)
			(layer "B.Fab")
		)
		(fp_line
			(start 0.12065 -0.305054)
			(end 0.12065 -0.2794)
			(stroke
				(width 0.1)
				(type default)
			)
			(layer "B.Fab")
		)
		(fp_line
			(start -0.120396 0.3048)
			(end -0.120396 0.2794)
			(stroke
				(width 0.1)
				(type default)
			)
			(layer "B.Fab")
		)
		(fp_line
			(start -0.120396 0.2794)
			(end 0.12065 0.2794)
			(stroke
				(width 0.1)
				(type default)
			)
			(layer "B.Fab")
		)
		(fp_line
			(start -0.12065 -0.2794)
			(end -0.12065 -0.3048)
			(stroke
				(width 0.1)
				(type default)
			)
			(layer "B.Fab")
		)
		(fp_line
			(start -0.12065 -0.3048)
			(end -0.67945 -0.3048)
			(stroke
				(width 0.1)
				(type default)
			)
			(layer "B.Fab")
		)
		(fp_line
			(start -0.67945 0.3048)
			(end -0.120396 0.3048)
			(stroke
				(width 0.1)
				(type default)
			)
			(layer "B.Fab")
		)
		(fp_line
			(start -0.67945 -0.3048)
			(end -0.67945 0.3048)
			(stroke
				(width 0.1)
				(type default)
			)
			(layer "B.Fab")
		)
		(pad "1" smd circle
			(at 0.40005 0)
			(size 0 0)
			(layers "B.Cu" "B.Mask" "B.Paste")
			(net "I3C_SPD_DDRABCD_CPU0_LVC1_SCL_5")
		)
		(pad "2" smd circle
			(at -0.40005 0)
			(size 0 0)
			(layers "B.Cu" "B.Mask" "B.Paste")
			(net "I3C_SPD_DDRABCD_CPU0_LVC1_SCL")
		)
	)
)
